(kicad_pcb
	(version 20260206)
	(generator "pcbnew")
	(generator_version "10.0")
	(general
		(thickness 1.6)
		(legacy_teardrops no)
	)
	(paper "A4")
	(title_block
		(title "04192023_DAF0TMB3IC0_F0TG_MB_C_brd_V02_OCP.brd")
		(comment 1 "Grand Teton / footprints 5951-5957 of 8354")
	)
	(layers
		(0 "F.Cu" signal "TOP")
		(4 "In1.Cu" signal "GND")
		(6 "In2.Cu" signal "IN1")
		(8 "In3.Cu" signal "GND1")
		(10 "In4.Cu" signal "IN2")
		(12 "In5.Cu" signal "GND2")
		(14 "In6.Cu" signal "IN3")
		(16 "In7.Cu" signal "GND3")
		(18 "In8.Cu" signal "VCC")
		(20 "In9.Cu" signal "VCC1")
		(22 "In10.Cu" signal "GND4")
		(24 "In11.Cu" signal "IN4")
		(26 "In12.Cu" signal "GND5")
		(28 "In13.Cu" signal "IN5")
		(30 "In14.Cu" signal "GND6")
		(32 "In15.Cu" signal "IN6")
		(34 "In16.Cu" signal "GND7")
		(2 "B.Cu" signal "BOTTOM")
		(9 "F.Adhes" user "F.Adhesive")
		(11 "B.Adhes" user "B.Adhesive")
		(13 "F.Paste" user "Package Geometry/Pastemask Top")
		(15 "B.Paste" user "Package Geometry/Pastemask Bottom")
		(5 "F.SilkS" user "Ref Des/Silkscreen Top")
		(7 "B.SilkS" user "Ref Des/Silkscreen Bottom")
		(1 "F.Mask" user "Board Geometry/Soldermask Top")
		(3 "B.Mask" user "Board Geometry/Soldermask Bottom")
		(17 "Dwgs.User" user "User.Drawings")
		(19 "Cmts.User" user "User.Comments")
		(21 "Eco1.User" user "User.Eco1")
		(23 "Eco2.User" user "User.Eco2")
		(25 "Edge.Cuts" user "Board Geometry/Outline")
		(27 "Margin" user)
		(31 "F.CrtYd" user "Package Geometry/Place Bound Top")
		(29 "B.CrtYd" user "Package Geometry/Place Bound Bottom")
		(35 "F.Fab" user "Ref Des/Assembly Top")
		(33 "B.Fab" user "Ref Des/Assembly Bottom")
	)
	(footprint ""
		(layer "B.Cu")
		(at 101.414834 -245.487952 180)
		(property "Reference" "C2346"
			(at 0 0 0)
			(layer "B.SilkS")
			(hide yes)
			(effects
				(font
					(size 1.27 1.27)
				)
				(justify mirror)
			)
		)
		(property "Value" ""
			(at 0 0 0)
			(layer "B.Fab")
			(effects
				(font
					(size 1.27 1.27)
				)
				(justify mirror)
			)
		)
		(duplicate_pad_numbers_are_jumpers no)
		(fp_line
			(start 0.7874 0.4064)
			(end 0.7874 -0.4064)
			(stroke
				(width 0.1524)
				(type default)
			)
			(layer "B.SilkS")
		)
		(fp_line
			(start 0.7874 -0.4064)
			(end -0.7874 -0.4064)
			(stroke
				(width 0.1524)
				(type default)
			)
			(layer "B.SilkS")
		)
		(fp_line
			(start -0.7874 0.4064)
			(end 0.7874 0.4064)
			(stroke
				(width 0.1524)
				(type default)
			)
			(layer "B.SilkS")
		)
		(fp_line
			(start -0.7874 -0.4064)
			(end -0.7874 0.4064)
			(stroke
				(width 0.1524)
				(type default)
			)
			(layer "B.SilkS")
		)
		(fp_line
			(start 0.67945 0.3048)
			(end 0.67945 -0.305054)
			(stroke
				(width 0.1)
				(type default)
			)
			(layer "B.Fab")
		)
		(fp_line
			(start 0.67945 -0.305054)
			(end 0.12065 -0.305054)
			(stroke
				(width 0.1)
				(type default)
			)
			(layer "B.Fab")
		)
		(fp_line
			(start 0.12065 0.3048)
			(end 0.67945 0.3048)
			(stroke
				(width 0.1)
				(type default)
			)
			(layer "B.Fab")
		)
		(fp_line
			(start 0.12065 0.2794)
			(end 0.12065 0.3048)
			(stroke
				(width 0.1)
				(type default)
			)
			(layer "B.Fab")
		)
		(fp_line
			(start 0.12065 -0.2794)
			(end -0.12065 -0.2794)
			(stroke
				(width 0.1)
				(type default)
			)
			(layer "B.Fab")
		)
		(fp_line
			(start 0.12065 -0.305054)
			(end 0.12065 -0.2794)
			(stroke
				(width 0.1)
				(type default)
			)
			(layer "B.Fab")
		)
		(fp_line
			(start -0.120396 0.3048)
			(end -0.120396 0.2794)
			(stroke
				(width 0.1)
				(type default)
			)
			(layer "B.Fab")
		)
		(fp_line
			(start -0.120396 0.2794)
			(end 0.12065 0.2794)
			(stroke
				(width 0.1)
				(type default)
			)
			(layer "B.Fab")
		)
		(fp_line
			(start -0.12065 -0.2794)
			(end -0.12065 -0.3048)
			(stroke
				(width 0.1)
				(type default)
			)
			(layer "B.Fab")
		)
		(fp_line
			(start -0.12065 -0.3048)
			(end -0.67945 -0.3048)
			(stroke
				(width 0.1)
				(type default)
			)
			(layer "B.Fab")
		)
		(fp_line
			(start -0.67945 0.3048)
			(end -0.120396 0.3048)
			(stroke
				(width 0.1)
				(type default)
			)
			(layer "B.Fab")
		)
		(fp_line
			(start -0.67945 -0.3048)
			(end -0.67945 0.3048)
			(stroke
				(width 0.1)
				(type default)
			)
			(layer "B.Fab")
		)
		(pad "1" smd circle
			(at 0.40005 0)
			(size 0 0)
			(layers "B.Cu" "B.Mask" "B.Paste")
			(net "PVDDCR_CPU0_P1")
		)
		(pad "2" smd circle
			(at -0.40005 0)
			(size 0 0)
			(layers "B.Cu" "B.Mask" "B.Paste")
			(net "GND")
		)
	)
	(footprint ""
		(layer "B.Cu")
		(at 422.19245 -428.757334 180)
		(property "Reference" "C1071"
			(at 0 0 0)
			(layer "B.SilkS")
			(hide yes)
			(effects
				(font
					(size 1.27 1.27)
				)
				(justify mirror)
			)
		)
		(property "Value" ""
			(at 0 0 0)
			(layer "B.Fab")
			(effects
				(font
					(size 1.27 1.27)
				)
				(justify mirror)
			)
		)
		(duplicate_pad_numbers_are_jumpers no)
		(fp_line
			(start 0.299974 0.150114)
			(end 0.299974 -0.150114)
			(stroke
				(width 0.1)
				(type default)
			)
			(layer "B.Fab")
		)
		(fp_line
			(start 0.299974 -0.150114)
			(end -0.299974 -0.150114)
			(stroke
				(width 0.1)
				(type default)
			)
			(layer "B.Fab")
		)
		(fp_line
			(start -0.299974 0.150114)
			(end 0.299974 0.150114)
			(stroke
				(width 0.1)
				(type default)
			)
			(layer "B.Fab")
		)
		(fp_line
			(start -0.299974 -0.150114)
			(end -0.299974 0.150114)
			(stroke
				(width 0.1)
				(type default)
			)
			(layer "B.Fab")
		)
		(pad "1" smd rect
			(at 0.2667 0)
			(size 0.3048 0.381)
			(layers "B.Cu" "B.Mask" "B.Paste")
			(net "P3V3_AUX")
		)
		(pad "2" smd rect
			(at -0.2667 0)
			(size 0.3048 0.381)
			(layers "B.Cu" "B.Mask" "B.Paste")
			(net "GND")
		)
	)
	(footprint ""
		(layer "B.Cu")
		(at 479.088958 -437.516778 180)
		(property "Reference" "DB11"
			(at 2.581402 -8.320786 270)
			(unlocked yes)
			(layer "B.SilkS")
			(effects
				(font
					(size 0.7874 0.5842)
					(thickness 0.1524)
				)
				(justify left mirror)
			)
		)
		(property "Value" ""
			(at 0 0 0)
			(layer "B.Fab")
			(effects
				(font
					(size 1.27 1.27)
				)
				(justify mirror)
			)
		)
		(duplicate_pad_numbers_are_jumpers no)
		(fp_line
			(start 3.330702 -4.771136)
			(end -3.330702 -4.771136)
			(stroke
				(width 0.1524)
				(type default)
			)
			(layer "B.SilkS")
		)
		(fp_line
			(start 0 4.011168)
			(end 3.330702 -4.771136)
			(stroke
				(width 0.1524)
				(type default)
			)
			(layer "B.SilkS")
		)
		(fp_line
			(start -3.330702 -4.771136)
			(end 0 4.011168)
			(stroke
				(width 0.1524)
				(type default)
			)
			(layer "B.SilkS")
		)
		(fp_line
			(start 3.330702 -4.771136)
			(end -3.330702 -4.771136)
			(stroke
				(width 0.1)
				(type default)
			)
			(layer "B.Fab")
		)
		(fp_line
			(start 0 4.011168)
			(end 3.330702 -4.771136)
			(stroke
				(width 0.1)
				(type default)
			)
			(layer "B.Fab")
		)
		(fp_line
			(start -3.330702 -4.771136)
			(end 0 4.011168)
			(stroke
				(width 0.1)
				(type default)
			)
			(layer "B.Fab")
		)
		(pad "1" thru_hole circle
			(at 0 0)
			(size 2.159 2.159)
			(drill 1.7018)
			(layers "*.Cu" "*.Mask")
			(remove_unused_layers no)
			(net "T1_GND")
			(clearance 0.0254)
			(thermal_gap 0.0254)
		)
		(pad "2" thru_hole circle
			(at 1.27 -3.348736)
			(size 2.159 2.159)
			(drill 1.7018)
			(layers "*.Cu" "*.Mask")
			(remove_unused_layers no)
			(net "TDR_SE_50_OHM_IN4")
			(clearance 0.0254)
			(thermal_gap 0.0254)
		)
		(pad "3" thru_hole circle
			(at -1.27 -3.348736)
			(size 2.159 2.159)
			(drill 1.7018)
			(layers "*.Cu" "*.Mask")
			(remove_unused_layers no)
			(net "TDR_SE_50_OHM_IN4")
			(clearance 0.0254)
			(thermal_gap 0.0254)
		)
	)
	(footprint ""
		(layer "B.Cu")
		(at 347.040454 -255.84531 180)
		(property "Reference" "C2524"
			(at 0 0 0)
			(layer "B.SilkS")
			(hide yes)
			(effects
				(font
					(size 1.27 1.27)
				)
				(justify mirror)
			)
		)
		(property "Value" ""
			(at 0 0 0)
			(layer "B.Fab")
			(effects
				(font
					(size 1.27 1.27)
				)
				(justify mirror)
			)
		)
		(duplicate_pad_numbers_are_jumpers no)
		(fp_line
			(start 0.7874 0.4064)
			(end 0.7874 -0.4064)
			(stroke
				(width 0.1524)
				(type default)
			)
			(layer "B.SilkS")
		)
		(fp_line
			(start 0.7874 -0.4064)
			(end -0.7874 -0.4064)
			(stroke
				(width 0.1524)
				(type default)
			)
			(layer "B.SilkS")
		)
		(fp_line
			(start -0.7874 0.4064)
			(end 0.7874 0.4064)
			(stroke
				(width 0.1524)
				(type default)
			)
			(layer "B.SilkS")
		)
		(fp_line
			(start -0.7874 -0.4064)
			(end -0.7874 0.4064)
			(stroke
				(width 0.1524)
				(type default)
			)
			(layer "B.SilkS")
		)
		(fp_line
			(start 0.67945 0.3048)
			(end 0.67945 -0.305054)
			(stroke
				(width 0.1)
				(type default)
			)
			(layer "B.Fab")
		)
		(fp_line
			(start 0.67945 -0.305054)
			(end 0.12065 -0.305054)
			(stroke
				(width 0.1)
				(type default)
			)
			(layer "B.Fab")
		)
		(fp_line
			(start 0.12065 0.3048)
			(end 0.67945 0.3048)
			(stroke
				(width 0.1)
				(type default)
			)
			(layer "B.Fab")
		)
		(fp_line
			(start 0.12065 0.2794)
			(end 0.12065 0.3048)
			(stroke
				(width 0.1)
				(type default)
			)
			(layer "B.Fab")
		)
		(fp_line
			(start 0.12065 -0.2794)
			(end -0.12065 -0.2794)
			(stroke
				(width 0.1)
				(type default)
			)
			(layer "B.Fab")
		)
		(fp_line
			(start 0.12065 -0.305054)
			(end 0.12065 -0.2794)
			(stroke
				(width 0.1)
				(type default)
			)
			(layer "B.Fab")
		)
		(fp_line
			(start -0.120396 0.3048)
			(end -0.120396 0.2794)
			(stroke
				(width 0.1)
				(type default)
			)
			(layer "B.Fab")
		)
		(fp_line
			(start -0.120396 0.2794)
			(end 0.12065 0.2794)
			(stroke
				(width 0.1)
				(type default)
			)
			(layer "B.Fab")
		)
		(fp_line
			(start -0.12065 -0.2794)
			(end -0.12065 -0.3048)
			(stroke
				(width 0.1)
				(type default)
			)
			(layer "B.Fab")
		)
		(fp_line
			(start -0.12065 -0.3048)
			(end -0.67945 -0.3048)
			(stroke
				(width 0.1)
				(type default)
			)
			(layer "B.Fab")
		)
		(fp_line
			(start -0.67945 0.3048)
			(end -0.120396 0.3048)
			(stroke
				(width 0.1)
				(type default)
			)
			(layer "B.Fab")
		)
		(fp_line
			(start -0.67945 -0.3048)
			(end -0.67945 0.3048)
			(stroke
				(width 0.1)
				(type default)
			)
			(layer "B.Fab")
		)
		(pad "1" smd circle
			(at 0.40005 0)
			(size 0 0)
			(layers "B.Cu" "B.Mask" "B.Paste")
			(net "PVDD18_S5_P0")
		)
		(pad "2" smd circle
			(at -0.40005 0)
			(size 0 0)
			(layers "B.Cu" "B.Mask" "B.Paste")
			(net "GND")
		)
	)
	(footprint ""
		(layer "B.Cu")
		(at 387.278626 -395.148562 90)
		(property "Reference" "C1027"
			(at 0 0 90)
			(layer "B.SilkS")
			(hide yes)
			(effects
				(font
					(size 1.27 1.27)
				)
				(justify mirror)
			)
		)
		(property "Value" ""
			(at 0 0 90)
			(layer "B.Fab")
			(effects
				(font
					(size 1.27 1.27)
				)
				(justify mirror)
			)
		)
		(duplicate_pad_numbers_are_jumpers no)
		(fp_line
			(start 0.299974 -0.150114)
			(end -0.299974 -0.150114)
			(stroke
				(width 0.1)
				(type default)
			)
			(layer "B.Fab")
		)
		(fp_line
			(start -0.299974 -0.150114)
			(end -0.299974 0.150114)
			(stroke
				(width 0.1)
				(type default)
			)
			(layer "B.Fab")
		)
		(fp_line
			(start 0.299974 0.150114)
			(end 0.299974 -0.150114)
			(stroke
				(width 0.1)
				(type default)
			)
			(layer "B.Fab")
		)
		(fp_line
			(start -0.299974 0.150114)
			(end 0.299974 0.150114)
			(stroke
				(width 0.1)
				(type default)
			)
			(layer "B.Fab")
		)
		(pad "1" smd rect
			(at 0.2667 0 270)
			(size 0.3048 0.381)
			(layers "B.Cu" "B.Mask" "B.Paste")
			(net "P0V9_CPU0_RT3_2A")
		)
		(pad "2" smd rect
			(at -0.2667 0 270)
			(size 0.3048 0.381)
			(layers "B.Cu" "B.Mask" "B.Paste")
			(net "GND")
		)
	)
	(footprint ""
		(layer "B.Cu")
		(at 184.480708 -422.208452 90)
		(property "Reference" "C8015"
			(at 0 0 90)
			(layer "B.SilkS")
			(hide yes)
			(effects
				(font
					(size 1.27 1.27)
				)
				(justify mirror)
			)
		)
		(property "Value" ""
			(at 0 0 90)
			(layer "B.Fab")
			(effects
				(font
					(size 1.27 1.27)
				)
				(justify mirror)
			)
		)
		(duplicate_pad_numbers_are_jumpers no)
		(fp_line
			(start 0.7874 -0.4064)
			(end -0.7874 -0.4064)
			(stroke
				(width 0.1524)
				(type default)
			)
			(layer "B.SilkS")
		)
		(fp_line
			(start -0.7874 -0.4064)
			(end -0.7874 0.4064)
			(stroke
				(width 0.1524)
				(type default)
			)
			(layer "B.SilkS")
		)
		(fp_line
			(start 0.7874 0.4064)
			(end 0.7874 -0.4064)
			(stroke
				(width 0.1524)
				(type default)
			)
			(layer "B.SilkS")
		)
		(fp_line
			(start -0.7874 0.4064)
			(end 0.7874 0.4064)
			(stroke
				(width 0.1524)
				(type default)
			)
			(layer "B.SilkS")
		)
		(fp_line
			(start 0.67945 -0.305054)
			(end 0.12065 -0.305054)
			(stroke
				(width 0.1)
				(type default)
			)
			(layer "B.Fab")
		)
		(fp_line
			(start 0.12065 -0.305054)
			(end 0.12065 -0.2794)
			(stroke
				(width 0.1)
				(type default)
			)
			(layer "B.Fab")
		)
		(fp_line
			(start -0.12065 -0.3048)
			(end -0.67945 -0.3048)
			(stroke
				(width 0.1)
				(type default)
			)
			(layer "B.Fab")
		)
		(fp_line
			(start -0.67945 -0.3048)
			(end -0.67945 0.3048)
			(stroke
				(width 0.1)
				(type default)
			)
			(layer "B.Fab")
		)
		(fp_line
			(start 0.12065 -0.2794)
			(end -0.12065 -0.2794)
			(stroke
				(width 0.1)
				(type default)
			)
			(layer "B.Fab")
		)
		(fp_line
			(start -0.12065 -0.2794)
			(end -0.12065 -0.3048)
			(stroke
				(width 0.1)
				(type default)
			)
			(layer "B.Fab")
		)
		(fp_line
			(start 0.12065 0.2794)
			(end 0.12065 0.3048)
			(stroke
				(width 0.1)
				(type default)
			)
			(layer "B.Fab")
		)
		(fp_line
			(start -0.120396 0.2794)
			(end 0.12065 0.2794)
			(stroke
				(width 0.1)
				(type default)
			)
			(layer "B.Fab")
		)
		(fp_line
			(start 0.67945 0.3048)
			(end 0.67945 -0.305054)
			(stroke
				(width 0.1)
				(type default)
			)
			(layer "B.Fab")
		)
		(fp_line
			(start 0.12065 0.3048)
			(end 0.67945 0.3048)
			(stroke
				(width 0.1)
				(type default)
			)
			(layer "B.Fab")
		)
		(fp_line
			(start -0.120396 0.3048)
			(end -0.120396 0.2794)
			(stroke
				(width 0.1)
				(type default)
			)
			(layer "B.Fab")
		)
		(fp_line
			(start -0.67945 0.3048)
			(end -0.120396 0.3048)
			(stroke
				(width 0.1)
				(type default)
			)
			(layer "B.Fab")
		)
		(pad "1" smd circle
			(at 0.40005 0 270)
			(size 0 0)
			(layers "B.Cu" "B.Mask" "B.Paste")
			(net "HSC_OC_VOL")
		)
		(pad "2" smd circle
			(at -0.40005 0 270)
			(size 0 0)
			(layers "B.Cu" "B.Mask" "B.Paste")
			(net "GND")
		)
	)
	(footprint ""
		(layer "B.Cu")
		(at 231.034082 -328.25182)
		(property "Reference" "R1254"
			(at 0 0 0)
			(layer "B.SilkS")
			(hide yes)
			(effects
				(font
					(size 1.27 1.27)
				)
				(justify mirror)
			)
		)
		(property "Value" ""
			(at 0 0 0)
			(layer "B.Fab")
			(effects
				(font
					(size 1.27 1.27)
				)
				(justify mirror)
			)
		)
		(duplicate_pad_numbers_are_jumpers no)
		(fp_line
			(start -0.7874 -0.4064)
			(end -0.7874 0.4064)
			(stroke
				(width 0.1524)
				(type default)
			)
			(layer "B.SilkS")
		)
		(fp_line
			(start -0.7874 0.4064)
			(end 0.7874 0.4064)
			(stroke
				(width 0.1524)
				(type default)
			)
			(layer "B.SilkS")
		)
		(fp_line
			(start 0.7874 -0.4064)
			(end -0.7874 -0.4064)
			(stroke
				(width 0.1524)
				(type default)
			)
			(layer "B.SilkS")
		)
		(fp_line
			(start 0.7874 0.4064)
			(end 0.7874 -0.4064)
			(stroke
				(width 0.1524)
				(type default)
			)
			(layer "B.SilkS")
		)
		(fp_line
			(start -0.67945 -0.3048)
			(end -0.67945 0.3048)
			(stroke
				(width 0.1)
				(type default)
			)
			(layer "B.Fab")
		)
		(fp_line
			(start -0.67945 0.3048)
			(end -0.120396 0.3048)
			(stroke
				(width 0.1)
				(type default)
			)
			(layer "B.Fab")
		)
		(fp_line
			(start -0.12065 -0.3048)
			(end -0.67945 -0.3048)
			(stroke
				(width 0.1)
				(type default)
			)
			(layer "B.Fab")
		)
		(fp_line
			(start -0.12065 -0.2794)
			(end -0.12065 -0.3048)
			(stroke
				(width 0.1)
				(type default)
			)
			(layer "B.Fab")
		)
		(fp_line
			(start -0.120396 0.2794)
			(end 0.12065 0.2794)
			(stroke
				(width 0.1)
				(type default)
			)
			(layer "B.Fab")
		)
		(fp_line
			(start -0.120396 0.3048)
			(end -0.120396 0.2794)
			(stroke
				(width 0.1)
				(type default)
			)
			(layer "B.Fab")
		)
		(fp_line
			(start 0.12065 -0.305054)
			(end 0.12065 -0.2794)
			(stroke
				(width 0.1)
				(type default)
			)
			(layer "B.Fab")
		)
		(fp_line
			(start 0.12065 -0.2794)
			(end -0.12065 -0.2794)
			(stroke
				(width 0.1)
				(type default)
			)
			(layer "B.Fab")
		)
		(fp_line
			(start 0.12065 0.2794)
			(end 0.12065 0.3048)
			(stroke
				(width 0.1)
				(type default)
			)
			(layer "B.Fab")
		)
		(fp_line
			(start 0.12065 0.3048)
			(end 0.67945 0.3048)
			(stroke
				(width 0.1)
				(type default)
			)
			(layer "B.Fab")
		)
		(fp_line
			(start 0.67945 -0.305054)
			(end 0.12065 -0.305054)
			(stroke
				(width 0.1)
				(type default)
			)
			(layer "B.Fab")
		)
		(fp_line
			(start 0.67945 0.3048)
			(end 0.67945 -0.305054)
			(stroke
				(width 0.1)
				(type default)
			)
			(layer "B.Fab")
		)
		(pad "1" smd rect
			(at 0.40005 0)
			(size 0.4572 0.508)
			(layers "B.Cu" "B.Mask" "B.Paste")
			(net "PVDD18_S5_P0_ADC")
		)
		(pad "2" smd rect
			(at -0.40005 0)
			(size 0.4572 0.508)
			(layers "B.Cu" "B.Mask" "B.Paste")
			(net "PVDD18_S5_P0_ADC_TIC")
		)
	)
)
